# S9S_MB_2U (Grand Teton) — schematic netlist excerpt (pin names and nets, part order shuffled) for the footprints in the layout excerpt that follows; sources: Cadence DE-HDL packaged netlist, KiCad conversion of 03242023_DA0F0TMBIJ0_F0T_Motherboard_J_brd_V01_OCP.brd

R4154  Q_RES  100K 1% EMPTY  pkg 0402LF  page 146 : A = PRSNT_CABLE_GPU_A1_N ; B = GND
R2369  Q_RES  0 5% CHIP  pkg 0402LF  page 266 : A = SVID_DIO0_CPU0_R ; B = SVID_DIO_PVCCIN_CPU0_R

(kicad_pcb
	(version 20260206)
	(generator "pcbnew")
	(generator_version "10.0")
	(general
		(thickness 1.6)
		(legacy_teardrops no)
	)
	(paper "A4")
	(title_block
		(title "03242023_DA0F0TMBIJ0_F0T_Motherboard_J_brd_V01_OCP.brd")
		(comment 1 "Grand Teton / footprints 2216-2217 of 6105")
	)
	(layers
		(0 "F.Cu" signal "TOP")
		(4 "In1.Cu" signal "GND")
		(6 "In2.Cu" signal "IN1")
		(8 "In3.Cu" signal "GND1")
		(10 "In4.Cu" signal "IN2")
		(12 "In5.Cu" signal "GND2")
		(14 "In6.Cu" signal "IN3")
		(16 "In7.Cu" signal "GND3")
		(18 "In8.Cu" signal "VCC")
		(20 "In9.Cu" signal "VCC1")
		(22 "In10.Cu" signal "GND4")
		(24 "In11.Cu" signal "IN4")
		(26 "In12.Cu" signal "GND5")
		(28 "In13.Cu" signal "IN5")
		(30 "In14.Cu" signal "GND6")
		(32 "In15.Cu" signal "IN6")
		(34 "In16.Cu" signal "GND7")
		(2 "B.Cu" signal "BOTTOM")
		(9 "F.Adhes" user "F.Adhesive")
		(11 "B.Adhes" user "B.Adhesive")
		(13 "F.Paste" user "Package Geometry/Pastemask Top")
		(15 "B.Paste" user "Package Geometry/Pastemask Bottom")
		(5 "F.SilkS" user "Ref Des/Silkscreen Top")
		(7 "B.SilkS" user "Ref Des/Silkscreen Bottom")
		(1 "F.Mask" user "Board Geometry/Soldermask Top")
		(3 "B.Mask" user "Board Geometry/Soldermask Bottom")
		(17 "Dwgs.User" user "User.Drawings")
		(19 "Cmts.User" user "User.Comments")
		(21 "Eco1.User" user "User.Eco1")
		(23 "Eco2.User" user "User.Eco2")
		(25 "Edge.Cuts" user "Board Geometry/Outline")
		(27 "Margin" user)
		(31 "F.CrtYd" user "Package Geometry/Place Bound Top")
		(29 "B.CrtYd" user "Package Geometry/Place Bound Bottom")
		(35 "F.Fab" user "Ref Des/Assembly Top")
		(33 "B.Fab" user "Ref Des/Assembly Bottom")
	)
	(footprint ""
		(layer "F.Cu")
		(at 294.62222 -419.02761 -90)
		(property "Reference" "R4154"
			(at 0 0 270)
			(layer "F.SilkS")
			(hide yes)
			(effects
				(font
					(size 1.27 1.27)
				)
			)
		)
		(property "Value" ""
			(at 0 0 270)
			(layer "F.Fab")
			(effects
				(font
					(size 1.27 1.27)
				)
			)
		)
		(duplicate_pad_numbers_are_jumpers no)
		(fp_line
			(start -0.7874 0.4064)
			(end -0.7874 -0.4064)
			(stroke
				(width 0.1524)
				(type default)
			)
			(layer "F.SilkS")
		)
		(fp_line
			(start 0.7874 0.4064)
			(end -0.7874 0.4064)
			(stroke
				(width 0.1524)
				(type default)
			)
			(layer "F.SilkS")
		)
		(fp_line
			(start -0.7874 -0.4064)
			(end 0.7874 -0.4064)
			(stroke
				(width 0.1524)
				(type default)
			)
			(layer "F.SilkS")
		)
		(fp_line
			(start 0.7874 -0.4064)
			(end 0.7874 0.4064)
			(stroke
				(width 0.1524)
				(type default)
			)
			(layer "F.SilkS")
		)
		(fp_line
			(start -0.67945 0.3048)
			(end -0.67945 -0.305054)
			(stroke
				(width 0.1)
				(type default)
			)
			(layer "F.Fab")
		)
		(fp_line
			(start -0.12065 0.3048)
			(end -0.67945 0.3048)
			(stroke
				(width 0.1)
				(type default)
			)
			(layer "F.Fab")
		)
		(fp_line
			(start 0.120396 0.3048)
			(end 0.120396 0.2794)
			(stroke
				(width 0.1)
				(type default)
			)
			(layer "F.Fab")
		)
		(fp_line
			(start 0.67945 0.3048)
			(end 0.120396 0.3048)
			(stroke
				(width 0.1)
				(type default)
			)
			(layer "F.Fab")
		)
		(fp_line
			(start -0.12065 0.2794)
			(end -0.12065 0.3048)
			(stroke
				(width 0.1)
				(type default)
			)
			(layer "F.Fab")
		)
		(fp_line
			(start 0.120396 0.2794)
			(end -0.12065 0.2794)
			(stroke
				(width 0.1)
				(type default)
			)
			(layer "F.Fab")
		)
		(fp_line
			(start -0.12065 -0.2794)
			(end 0.12065 -0.2794)
			(stroke
				(width 0.1)
				(type default)
			)
			(layer "F.Fab")
		)
		(fp_line
			(start 0.12065 -0.2794)
			(end 0.12065 -0.3048)
			(stroke
				(width 0.1)
				(type default)
			)
			(layer "F.Fab")
		)
		(fp_line
			(start 0.12065 -0.3048)
			(end 0.67945 -0.3048)
			(stroke
				(width 0.1)
				(type default)
			)
			(layer "F.Fab")
		)
		(fp_line
			(start 0.67945 -0.3048)
			(end 0.67945 0.3048)
			(stroke
				(width 0.1)
				(type default)
			)
			(layer "F.Fab")
		)
		(fp_line
			(start -0.67945 -0.305054)
			(end -0.12065 -0.305054)
			(stroke
				(width 0.1)
				(type default)
			)
			(layer "F.Fab")
		)
		(fp_line
			(start -0.12065 -0.305054)
			(end -0.12065 -0.2794)
			(stroke
				(width 0.1)
				(type default)
			)
			(layer "F.Fab")
		)
		(pad "1" smd circle
			(at -0.40005 0 270)
			(size 0 0)
			(layers "F.Cu" "F.Mask" "F.Paste")
			(net "PRSNT_CABLE_GPU_A1_N")
		)
		(pad "2" smd circle
			(at 0.40005 0 270)
			(size 0 0)
			(layers "F.Cu" "F.Mask" "F.Paste")
			(net "GND")
		)
	)
	(footprint ""
		(layer "F.Cu")
		(at 350.78543 -356.668578)
		(property "Reference" "R2369"
			(at 0 0 0)
			(layer "F.SilkS")
			(hide yes)
			(effects
				(font
					(size 1.27 1.27)
				)
			)
		)
		(property "Value" ""
			(at 0 0 0)
			(layer "F.Fab")
			(effects
				(font
					(size 1.27 1.27)
				)
			)
		)
		(duplicate_pad_numbers_are_jumpers no)
		(fp_line
			(start -0.7874 -0.4064)
			(end 0.7874 -0.4064)
			(stroke
				(width 0.1524)
				(type default)
			)
			(layer "F.SilkS")
		)
		(fp_line
			(start -0.7874 0.4064)
			(end -0.7874 -0.4064)
			(stroke
				(width 0.1524)
				(type default)
			)
			(layer "F.SilkS")
		)
		(fp_line
			(start 0.7874 -0.4064)
			(end 0.7874 0.4064)
			(stroke
				(width 0.1524)
				(type default)
			)
			(layer "F.SilkS")
		)
		(fp_line
			(start 0.7874 0.4064)
			(end -0.7874 0.4064)
			(stroke
				(width 0.1524)
				(type default)
			)
			(layer "F.SilkS")
		)
		(fp_line
			(start -0.67945 -0.305054)
			(end -0.12065 -0.305054)
			(stroke
				(width 0.1)
				(type default)
			)
			(layer "F.Fab")
		)
		(fp_line
			(start -0.67945 0.3048)
			(end -0.67945 -0.305054)
			(stroke
				(width 0.1)
				(type default)
			)
			(layer "F.Fab")
		)
		(fp_line
			(start -0.12065 -0.305054)
			(end -0.12065 -0.2794)
			(stroke
				(width 0.1)
				(type default)
			)
			(layer "F.Fab")
		)
		(fp_line
			(start -0.12065 -0.2794)
			(end 0.12065 -0.2794)
			(stroke
				(width 0.1)
				(type default)
			)
			(layer "F.Fab")
		)
		(fp_line
			(start -0.12065 0.2794)
			(end -0.12065 0.3048)
			(stroke
				(width 0.1)
				(type default)
			)
			(layer "F.Fab")
		)
		(fp_line
			(start -0.12065 0.3048)
			(end -0.67945 0.3048)
			(stroke
				(width 0.1)
				(type default)
			)
			(layer "F.Fab")
		)
		(fp_line
			(start 0.120396 0.2794)
			(end -0.12065 0.2794)
			(stroke
				(width 0.1)
				(type default)
			)
			(layer "F.Fab")
		)
		(fp_line
			(start 0.120396 0.3048)
			(end 0.120396 0.2794)
			(stroke
				(width 0.1)
				(type default)
			)
			(layer "F.Fab")
		)
		(fp_line
			(start 0.12065 -0.3048)
			(end 0.67945 -0.3048)
			(stroke
				(width 0.1)
				(type default)
			)
			(layer "F.Fab")
		)
		(fp_line
			(start 0.12065 -0.2794)
			(end 0.12065 -0.3048)
			(stroke
				(width 0.1)
				(type default)
			)
			(layer "F.Fab")
		)
		(fp_line
			(start 0.67945 -0.3048)
			(end 0.67945 0.3048)
			(stroke
				(width 0.1)
				(type default)
			)
			(layer "F.Fab")
		)
		(fp_line
			(start 0.67945 0.3048)
			(end 0.120396 0.3048)
			(stroke
				(width 0.1)
				(type default)
			)
			(layer "F.Fab")
		)
		(pad "1" smd circle
			(at -0.40005 0)
			(size 0 0)
			(layers "F.Cu" "F.Mask" "F.Paste")
			(net "SVID_DIO0_CPU0_R")
		)
		(pad "2" smd circle
			(at 0.40005 0)
			(size 0 0)
			(layers "F.Cu" "F.Mask" "F.Paste")
			(net "SVID_DIO_PVCCIN_CPU0_R")
		)
	)
)
